# T6G (Grand Teton) — schematic netlist excerpt (pin names and nets, part order shuffled) for the footprints in the layout excerpt that follows; sources: Cadence DE-HDL packaged netlist, KiCad conversion of 04192023_DAF0TMB3IC0_F0TG_MB_C_brd_V02_OCP.brd

U60  SCHOTTKY_DUAL_12A_3C  BAT54CW EMPTY  pkg SOT323  page 169
  B  = P3V3_AUX_DSC_VOL
  A  = NC
  C  = P3V3_AUX_DSC_S1

C6531  Q_CAP_DIFFBUS  DIFF BUS_0.22UF 6.3V 20% X6S  pkg C0201  page 275 : \1\ = P5E_CPU0_P0_TX_BUF_C_DP<15> ; \2\ = P5E_CPU0_P0_TX_BUF_DP<15>
PC6555_1  Q_CAP  3300PF 50V 10% X7R  pkg 0402  page 363 : A = SW_P12V_AUX_P0V9_RETIMER_CPU0_FLT ; B = GND

(kicad_pcb
	(version 20260206)
	(generator "pcbnew")
	(generator_version "10.0")
	(general
		(thickness 1.6)
		(legacy_teardrops no)
	)
	(paper "A4")
	(title_block
		(title "04192023_DAF0TMB3IC0_F0TG_MB_C_brd_V02_OCP.brd")
		(comment 1 "Grand Teton / footprints 1597-1599 of 8354")
	)
	(layers
		(0 "F.Cu" signal "TOP")
		(4 "In1.Cu" signal "GND")
		(6 "In2.Cu" signal "IN1")
		(8 "In3.Cu" signal "GND1")
		(10 "In4.Cu" signal "IN2")
		(12 "In5.Cu" signal "GND2")
		(14 "In6.Cu" signal "IN3")
		(16 "In7.Cu" signal "GND3")
		(18 "In8.Cu" signal "VCC")
		(20 "In9.Cu" signal "VCC1")
		(22 "In10.Cu" signal "GND4")
		(24 "In11.Cu" signal "IN4")
		(26 "In12.Cu" signal "GND5")
		(28 "In13.Cu" signal "IN5")
		(30 "In14.Cu" signal "GND6")
		(32 "In15.Cu" signal "IN6")
		(34 "In16.Cu" signal "GND7")
		(2 "B.Cu" signal "BOTTOM")
		(9 "F.Adhes" user "F.Adhesive")
		(11 "B.Adhes" user "B.Adhesive")
		(13 "F.Paste" user "Package Geometry/Pastemask Top")
		(15 "B.Paste" user "Package Geometry/Pastemask Bottom")
		(5 "F.SilkS" user "Ref Des/Silkscreen Top")
		(7 "B.SilkS" user "Ref Des/Silkscreen Bottom")
		(1 "F.Mask" user "Board Geometry/Soldermask Top")
		(3 "B.Mask" user "Board Geometry/Soldermask Bottom")
		(17 "Dwgs.User" user "User.Drawings")
		(19 "Cmts.User" user "User.Comments")
		(21 "Eco1.User" user "User.Eco1")
		(23 "Eco2.User" user "User.Eco2")
		(25 "Edge.Cuts" user "Board Geometry/Outline")
		(27 "Margin" user)
		(31 "F.CrtYd" user "Package Geometry/Place Bound Top")
		(29 "B.CrtYd" user "Package Geometry/Place Bound Bottom")
		(35 "F.Fab" user "Ref Des/Assembly Top")
		(33 "B.Fab" user "Ref Des/Assembly Bottom")
	)
	(footprint ""
		(layer "F.Cu")
		(at 448.939666 -401.93087)
		(property "Reference" "PC6555_1"
			(at 0 0 0)
			(layer "F.SilkS")
			(hide yes)
			(effects
				(font
					(size 1.27 1.27)
				)
			)
		)
		(property "Value" ""
			(at 0 0 0)
			(layer "F.Fab")
			(effects
				(font
					(size 1.27 1.27)
				)
			)
		)
		(duplicate_pad_numbers_are_jumpers no)
		(fp_line
			(start -0.7874 -0.4064)
			(end 0.7874 -0.4064)
			(stroke
				(width 0.1524)
				(type default)
			)
			(layer "F.SilkS")
		)
		(fp_line
			(start -0.7874 0.4064)
			(end -0.7874 -0.4064)
			(stroke
				(width 0.1524)
				(type default)
			)
			(layer "F.SilkS")
		)
		(fp_line
			(start 0.7874 -0.4064)
			(end 0.7874 0.4064)
			(stroke
				(width 0.1524)
				(type default)
			)
			(layer "F.SilkS")
		)
		(fp_line
			(start 0.7874 0.4064)
			(end -0.7874 0.4064)
			(stroke
				(width 0.1524)
				(type default)
			)
			(layer "F.SilkS")
		)
		(fp_line
			(start -0.67945 -0.305054)
			(end -0.12065 -0.305054)
			(stroke
				(width 0.1)
				(type default)
			)
			(layer "F.Fab")
		)
		(fp_line
			(start -0.67945 0.3048)
			(end -0.67945 -0.305054)
			(stroke
				(width 0.1)
				(type default)
			)
			(layer "F.Fab")
		)
		(fp_line
			(start -0.12065 -0.305054)
			(end -0.12065 -0.2794)
			(stroke
				(width 0.1)
				(type default)
			)
			(layer "F.Fab")
		)
		(fp_line
			(start -0.12065 -0.2794)
			(end 0.12065 -0.2794)
			(stroke
				(width 0.1)
				(type default)
			)
			(layer "F.Fab")
		)
		(fp_line
			(start -0.12065 0.2794)
			(end -0.12065 0.3048)
			(stroke
				(width 0.1)
				(type default)
			)
			(layer "F.Fab")
		)
		(fp_line
			(start -0.12065 0.3048)
			(end -0.67945 0.3048)
			(stroke
				(width 0.1)
				(type default)
			)
			(layer "F.Fab")
		)
		(fp_line
			(start 0.120396 0.2794)
			(end -0.12065 0.2794)
			(stroke
				(width 0.1)
				(type default)
			)
			(layer "F.Fab")
		)
		(fp_line
			(start 0.120396 0.3048)
			(end 0.120396 0.2794)
			(stroke
				(width 0.1)
				(type default)
			)
			(layer "F.Fab")
		)
		(fp_line
			(start 0.12065 -0.3048)
			(end 0.67945 -0.3048)
			(stroke
				(width 0.1)
				(type default)
			)
			(layer "F.Fab")
		)
		(fp_line
			(start 0.12065 -0.2794)
			(end 0.12065 -0.3048)
			(stroke
				(width 0.1)
				(type default)
			)
			(layer "F.Fab")
		)
		(fp_line
			(start 0.67945 -0.3048)
			(end 0.67945 0.3048)
			(stroke
				(width 0.1)
				(type default)
			)
			(layer "F.Fab")
		)
		(fp_line
			(start 0.67945 0.3048)
			(end 0.120396 0.3048)
			(stroke
				(width 0.1)
				(type default)
			)
			(layer "F.Fab")
		)
		(pad "1" smd circle
			(at -0.40005 0)
			(size 0 0)
			(layers "F.Cu" "F.Mask" "F.Paste")
			(net "SW_P12V_AUX_P0V9_RETIMER_CPU0_FLT")
		)
		(pad "2" smd circle
			(at 0.40005 0)
			(size 0 0)
			(layers "F.Cu" "F.Mask" "F.Paste")
			(net "GND")
		)
	)
	(footprint ""
		(layer "F.Cu")
		(at 350.631506 -416.899344 -90)
		(property "Reference" "C6531"
			(at 0 0 270)
			(layer "F.SilkS")
			(hide yes)
			(effects
				(font
					(size 1.27 1.27)
				)
			)
		)
		(property "Value" ""
			(at 0 0 270)
			(layer "F.Fab")
			(effects
				(font
					(size 1.27 1.27)
				)
			)
		)
		(duplicate_pad_numbers_are_jumpers no)
		(fp_line
			(start -0.299974 0.150114)
			(end -0.299974 -0.150114)
			(stroke
				(width 0.1)
				(type default)
			)
			(layer "F.Fab")
		)
		(fp_line
			(start 0.299974 0.150114)
			(end -0.299974 0.150114)
			(stroke
				(width 0.1)
				(type default)
			)
			(layer "F.Fab")
		)
		(fp_line
			(start -0.299974 -0.150114)
			(end 0.299974 -0.150114)
			(stroke
				(width 0.1)
				(type default)
			)
			(layer "F.Fab")
		)
		(fp_line
			(start 0.299974 -0.150114)
			(end 0.299974 0.150114)
			(stroke
				(width 0.1)
				(type default)
			)
			(layer "F.Fab")
		)
		(pad "1" smd rect
			(at -0.2667 0 270)
			(size 0.3048 0.381)
			(layers "F.Cu" "F.Mask" "F.Paste")
			(net "P5E_CPU0_P0_TX_BUF_C_DP<15>")
		)
		(pad "2" smd rect
			(at 0.2667 0 270)
			(size 0.3048 0.381)
			(layers "F.Cu" "F.Mask" "F.Paste")
			(net "P5E_CPU0_P0_TX_BUF_DP<15>")
		)
	)
	(footprint ""
		(layer "F.Cu")
		(at 47.45482 -102.41534 90)
		(property "Reference" "U60"
			(at -1.25476 -1.89357 90)
			(unlocked yes)
			(layer "F.SilkS")
			(effects
				(font
					(size 0.7874 0.5842)
					(thickness 0.1524)
				)
				(justify left)
			)
		)
		(property "Value" ""
			(at 0 0 90)
			(layer "F.Fab")
			(effects
				(font
					(size 1.27 1.27)
				)
			)
		)
		(duplicate_pad_numbers_are_jumpers no)
		(fp_line
			(start 1.335278 -1.100074)
			(end -1.335278 -1.100074)
			(stroke
				(width 0.1524)
				(type default)
			)
			(layer "F.SilkS")
		)
		(fp_line
			(start -1.335278 -1.100074)
			(end -1.335278 1.100074)
			(stroke
				(width 0.1524)
				(type default)
			)
			(layer "F.SilkS")
		)
		(fp_line
			(start 1.335278 1.100074)
			(end 1.335278 -1.100074)
			(stroke
				(width 0.1524)
				(type default)
			)
			(layer "F.SilkS")
		)
		(fp_line
			(start -1.335278 1.100074)
			(end 1.335278 1.100074)
			(stroke
				(width 0.1524)
				(type default)
			)
			(layer "F.SilkS")
		)
		(fp_line
			(start 0.674878 -1.100074)
			(end -0.674878 -1.100074)
			(stroke
				(width 0.1)
				(type default)
			)
			(layer "F.Fab")
		)
		(fp_line
			(start -0.674878 -1.100074)
			(end -0.674878 1.100074)
			(stroke
				(width 0.1)
				(type default)
			)
			(layer "F.Fab")
		)
		(fp_line
			(start 0.674878 1.100074)
			(end 0.674878 -1.100074)
			(stroke
				(width 0.1)
				(type default)
			)
			(layer "F.Fab")
		)
		(fp_line
			(start -0.674878 1.100074)
			(end 0.674878 1.100074)
			(stroke
				(width 0.1)
				(type default)
			)
			(layer "F.Fab")
		)
		(pad "1" smd rect
			(at -0.8001 0.649986)
			(size 0.6096 0.8128)
			(layers "F.Cu" "F.Mask" "F.Paste")
			(net "P3V3_AUX_DSC_VOL")
		)
		(pad "2" smd rect
			(at -0.8001 -0.649986)
			(size 0.6096 0.8128)
			(layers "F.Cu" "F.Mask" "F.Paste")
			(net "Net_10856")
		)
		(pad "3" smd rect
			(at 0.8001 0)
			(size 0.6096 0.8128)
			(layers "F.Cu" "F.Mask" "F.Paste")
			(net "P3V3_AUX_DSC_S1")
		)
	)
)
